(kicad_pcb
	(version 20241229)
	(generator "pcbnew")
	(generator_version "9.0")
	(general
		(thickness 1.62)
		(legacy_teardrops no)
	)
	(paper "A4")
	(title_block
		(title "OCuLink to 10GbE adapter")
		(date "2026-02-23")
		(rev "1.1.0")
		(company "Antmicro Ltd")
		(comment 1 "www.antmicro.com")
		(comment 9 "footprints 385-390 of 510")
	)
	(layers
		(0 "F.Cu" signal)
		(4 "In1.Cu" signal)
		(6 "In2.Cu" signal)
		(8 "In3.Cu" signal)
		(10 "In4.Cu" signal)
		(12 "In5.Cu" signal)
		(14 "In6.Cu" signal)
		(2 "B.Cu" signal)
		(9 "F.Adhes" user "F.Adhesive")
		(11 "B.Adhes" user "B.Adhesive")
		(13 "F.Paste" user)
		(15 "B.Paste" user)
		(5 "F.SilkS" user "F.Silkscreen")
		(7 "B.SilkS" user "B.Silkscreen")
		(1 "F.Mask" user)
		(3 "B.Mask" user)
		(17 "Dwgs.User" user "User.Drawings")
		(19 "Cmts.User" user "User.Comments")
		(21 "Eco1.User" user "User.Eco1")
		(23 "Eco2.User" user "User.Eco2")
		(25 "Edge.Cuts" user)
		(27 "Margin" user)
		(31 "F.CrtYd" user "F.Courtyard")
		(29 "B.CrtYd" user "B.Courtyard")
		(35 "F.Fab" user)
		(33 "B.Fab" user)
	)
	(footprint "antmicro-footprints:C_0402_1005Metric"
		(layer "B.Cu")
		(at 85.225 100.15 90)
		(descr "Capacitor SMD 0402")
		(tags "capacitor SMD 0402")
		(property "Reference" "C119"
			(at 9.87 -0.442343 90)
			(layer "B.SilkS")
			(effects
				(font
					(size 0.7 0.7)
					(thickness 0.15)
				)
				(justify right top mirror)
			)
		)
		(property "Value" "C_1u_25V_0402"
			(at -1.022927 -2.155213 90)
			(layer "B.Fab")
			(hide yes)
			(effects
				(font
					(size 0.7 0.7)
					(thickness 0.15)
				)
				(justify right top mirror)
			)
		)
		(property "Datasheet" "https://www.murata.com/products/productdetail?partno=GRM155R61E105KE11%23"
			(at 0 0 90)
			(layer "B.Fab")
			(hide yes)
			(effects
				(font
					(size 1.27 1.27)
					(thickness 0.15)
				)
				(justify mirror)
			)
		)
		(property "Description" "SMD Multilayer Ceramic Capacitor, 1 µF, 25 V, 0402 [1005 Metric], ± 10%, X5R, GRM Series"
			(at 0 0 90)
			(layer "B.Fab")
			(hide yes)
			(effects
				(font
					(size 1.27 1.27)
					(thickness 0.15)
				)
				(justify mirror)
			)
		)
		(property "MPN" "GRM155R61E105KE11J"
			(at 0 0 90)
			(unlocked yes)
			(layer "B.Fab")
			(hide yes)
			(effects
				(font
					(size 1 1)
					(thickness 0.15)
				)
				(justify mirror)
			)
		)
		(property "Manufacturer" "Murata"
			(at 0 0 90)
			(unlocked yes)
			(layer "B.Fab")
			(hide yes)
			(effects
				(font
					(size 1 1)
					(thickness 0.15)
				)
				(justify mirror)
			)
		)
		(property "License" "Apache-2.0"
			(at 0 0 90)
			(unlocked yes)
			(layer "B.Fab")
			(hide yes)
			(effects
				(font
					(size 1 1)
					(thickness 0.15)
				)
				(justify mirror)
			)
		)
		(property "Author" "Antmicro"
			(at 0 0 90)
			(unlocked yes)
			(layer "B.Fab")
			(hide yes)
			(effects
				(font
					(size 1 1)
					(thickness 0.15)
				)
				(justify mirror)
			)
		)
		(property "Val" "1u"
			(at 0 0 90)
			(unlocked yes)
			(layer "B.Fab")
			(hide yes)
			(effects
				(font
					(size 1 1)
					(thickness 0.15)
				)
				(justify mirror)
			)
		)
		(property "Voltage" "25V"
			(at 0 0 90)
			(unlocked yes)
			(layer "B.Fab")
			(hide yes)
			(effects
				(font
					(size 1 1)
					(thickness 0.15)
				)
				(justify mirror)
			)
		)
		(property "Dielectric" "X5R"
			(at 0 0 90)
			(unlocked yes)
			(layer "B.Fab")
			(hide yes)
			(effects
				(font
					(size 1 1)
					(thickness 0.15)
				)
				(justify mirror)
			)
		)
		(sheetname "/X710-AT2 power/")
		(sheetfile "x710-at2-power.kicad_sch")
		(attr smd)
		(fp_rect
			(start -0.925 0.47)
			(end 0.925 -0.47)
			(stroke
				(width 0.05)
				(type default)
			)
			(fill no)
			(layer "B.CrtYd")
		)
		(fp_line
			(start 0.504 -0.248)
			(end -0.494 -0.248)
			(stroke
				(width 0.15)
				(type solid)
			)
			(layer "B.Fab")
		)
		(fp_line
			(start -0.494 -0.248)
			(end -0.494 0.25)
			(stroke
				(width 0.15)
				(type solid)
			)
			(layer "B.Fab")
		)
		(fp_line
			(start 0.504 0.25)
			(end 0.504 -0.248)
			(stroke
				(width 0.15)
				(type solid)
			)
			(layer "B.Fab")
		)
		(fp_line
			(start -0.494 0.25)
			(end 0.504 0.25)
			(stroke
				(width 0.15)
				(type solid)
			)
			(layer "B.Fab")
		)
		(pad "1" smd roundrect
			(at -0.48 0 90)
			(size 0.59 0.64)
			(layers "B.Cu" "B.Mask" "B.Paste")
			(roundrect_rratio 0.25)
			(net 28 "GND")
			(pintype "passive")
		)
		(pad "2" smd roundrect
			(at 0.48 0 90)
			(size 0.59 0.64)
			(layers "B.Cu" "B.Mask" "B.Paste")
			(roundrect_rratio 0.25)
			(net 9 "VCCD")
			(pintype "passive")
		)
	)
	(footprint "antmicro-footprints:C_0402_1005Metric"
		(layer "B.Cu")
		(at 87.225 94.6 90)
		(descr "Capacitor SMD 0402")
		(tags "capacitor SMD 0402")
		(property "Reference" "C95"
			(at 12.5 -0.462343 90)
			(layer "B.SilkS")
			(effects
				(font
					(size 0.7 0.7)
					(thickness 0.15)
				)
				(justify right top mirror)
			)
		)
		(property "Value" "C_1u_25V_0402"
			(at -1.022927 -2.155213 90)
			(layer "B.Fab")
			(hide yes)
			(effects
				(font
					(size 0.7 0.7)
					(thickness 0.15)
				)
				(justify right top mirror)
			)
		)
		(property "Datasheet" "https://www.murata.com/products/productdetail?partno=GRM155R61E105KE11%23"
			(at 0 0 90)
			(layer "B.Fab")
			(hide yes)
			(effects
				(font
					(size 1.27 1.27)
					(thickness 0.15)
				)
				(justify mirror)
			)
		)
		(property "Description" "SMD Multilayer Ceramic Capacitor, 1 µF, 25 V, 0402 [1005 Metric], ± 10%, X5R, GRM Series"
			(at 0 0 90)
			(layer "B.Fab")
			(hide yes)
			(effects
				(font
					(size 1.27 1.27)
					(thickness 0.15)
				)
				(justify mirror)
			)
		)
		(property "MPN" "GRM155R61E105KE11J"
			(at 0 0 90)
			(unlocked yes)
			(layer "B.Fab")
			(hide yes)
			(effects
				(font
					(size 1 1)
					(thickness 0.15)
				)
				(justify mirror)
			)
		)
		(property "Manufacturer" "Murata"
			(at 0 0 90)
			(unlocked yes)
			(layer "B.Fab")
			(hide yes)
			(effects
				(font
					(size 1 1)
					(thickness 0.15)
				)
				(justify mirror)
			)
		)
		(property "License" "Apache-2.0"
			(at 0 0 90)
			(unlocked yes)
			(layer "B.Fab")
			(hide yes)
			(effects
				(font
					(size 1 1)
					(thickness 0.15)
				)
				(justify mirror)
			)
		)
		(property "Author" "Antmicro"
			(at 0 0 90)
			(unlocked yes)
			(layer "B.Fab")
			(hide yes)
			(effects
				(font
					(size 1 1)
					(thickness 0.15)
				)
				(justify mirror)
			)
		)
		(property "Val" "1u"
			(at 0 0 90)
			(unlocked yes)
			(layer "B.Fab")
			(hide yes)
			(effects
				(font
					(size 1 1)
					(thickness 0.15)
				)
				(justify mirror)
			)
		)
		(property "Voltage" "25V"
			(at 0 0 90)
			(unlocked yes)
			(layer "B.Fab")
			(hide yes)
			(effects
				(font
					(size 1 1)
					(thickness 0.15)
				)
				(justify mirror)
			)
		)
		(property "Dielectric" "X5R"
			(at 0 0 90)
			(unlocked yes)
			(layer "B.Fab")
			(hide yes)
			(effects
				(font
					(size 1 1)
					(thickness 0.15)
				)
				(justify mirror)
			)
		)
		(sheetname "/X710-AT2 power/")
		(sheetfile "x710-at2-power.kicad_sch")
		(attr smd)
		(fp_rect
			(start -0.925 0.47)
			(end 0.925 -0.47)
			(stroke
				(width 0.05)
				(type default)
			)
			(fill no)
			(layer "B.CrtYd")
		)
		(fp_line
			(start 0.504 -0.248)
			(end -0.494 -0.248)
			(stroke
				(width 0.15)
				(type solid)
			)
			(layer "B.Fab")
		)
		(fp_line
			(start -0.494 -0.248)
			(end -0.494 0.25)
			(stroke
				(width 0.15)
				(type solid)
			)
			(layer "B.Fab")
		)
		(fp_line
			(start 0.504 0.25)
			(end 0.504 -0.248)
			(stroke
				(width 0.15)
				(type solid)
			)
			(layer "B.Fab")
		)
		(fp_line
			(start -0.494 0.25)
			(end 0.504 0.25)
			(stroke
				(width 0.15)
				(type solid)
			)
			(layer "B.Fab")
		)
		(pad "1" smd roundrect
			(at -0.48 0 90)
			(size 0.59 0.64)
			(layers "B.Cu" "B.Mask" "B.Paste")
			(roundrect_rratio 0.25)
			(net 28 "GND")
			(pintype "passive")
		)
		(pad "2" smd roundrect
			(at 0.48 0 90)
			(size 0.59 0.64)
			(layers "B.Cu" "B.Mask" "B.Paste")
			(roundrect_rratio 0.25)
			(net 1 "VCCA")
			(pintype "passive")
		)
	)
	(footprint "antmicro-footprints:R_0402_1005Metric"
		(layer "B.Cu")
		(at 96.45 107.1 180)
		(descr "Resistor SMD 0402")
		(tags "resistor SMD 0402")
		(property "Reference" "R83"
			(at -0.9 0.25 0)
			(layer "B.SilkS")
			(effects
				(font
					(size 0.7 0.7)
					(thickness 0.15)
				)
				(justify right top mirror)
			)
		)
		(property "Value" "R_22R_0402"
			(at -1.011843 -1.772047 0)
			(layer "B.Fab")
			(hide yes)
			(effects
				(font
					(size 0.7 0.7)
					(thickness 0.15)
				)
				(justify left bottom mirror)
			)
		)
		(property "Datasheet" "https://www.bourns.com/docs/product-datasheets/cr.pdf"
			(at 0 0 0)
			(layer "B.Fab")
			(hide yes)
			(effects
				(font
					(size 1.27 1.27)
					(thickness 0.15)
				)
				(justify mirror)
			)
		)
		(property "Description" "SMD Chip Resistor, 22 ohm, ± 1%, 62.5 mW, 0402 [1005 Metric], Thick Film, General Purpose"
			(at 0 0 0)
			(layer "B.Fab")
			(hide yes)
			(effects
				(font
					(size 1.27 1.27)
					(thickness 0.15)
				)
				(justify mirror)
			)
		)
		(property "MPN" "CR0402-FX-22R0GLF"
			(at 0 0 180)
			(unlocked yes)
			(layer "B.Fab")
			(hide yes)
			(effects
				(font
					(size 1 1)
					(thickness 0.15)
				)
				(justify mirror)
			)
		)
		(property "Manufacturer" "Bourns"
			(at 0 0 180)
			(unlocked yes)
			(layer "B.Fab")
			(hide yes)
			(effects
				(font
					(size 1 1)
					(thickness 0.15)
				)
				(justify mirror)
			)
		)
		(property "License" "Apache-2.0"
			(at 0 0 180)
			(unlocked yes)
			(layer "B.Fab")
			(hide yes)
			(effects
				(font
					(size 1 1)
					(thickness 0.15)
				)
				(justify mirror)
			)
		)
		(property "Author" "Antmicro"
			(at 0 0 180)
			(unlocked yes)
			(layer "B.Fab")
			(hide yes)
			(effects
				(font
					(size 1 1)
					(thickness 0.15)
				)
				(justify mirror)
			)
		)
		(property "Val" "22R"
			(at 0 0 180)
			(unlocked yes)
			(layer "B.Fab")
			(hide yes)
			(effects
				(font
					(size 1 1)
					(thickness 0.15)
				)
				(justify mirror)
			)
		)
		(property "Tolerance" "1%"
			(at 0 0 180)
			(unlocked yes)
			(layer "B.Fab")
			(hide yes)
			(effects
				(font
					(size 1 1)
					(thickness 0.15)
				)
				(justify mirror)
			)
		)
		(sheetname "/X710-AT2 Misc/")
		(sheetfile "x710-at2-mics.kicad_sch")
		(attr smd)
		(fp_rect
			(start -0.925 0.47)
			(end 0.925 -0.47)
			(stroke
				(width 0.05)
				(type default)
			)
			(fill no)
			(layer "B.CrtYd")
		)
		(fp_rect
			(start -0.5 0.25)
			(end 0.5 -0.25)
			(stroke
				(width 0.15)
				(type solid)
			)
			(fill no)
			(layer "B.Fab")
		)
		(pad "1" smd roundrect
			(at -0.48 0 180)
			(size 0.59 0.64)
			(layers "B.Cu" "B.Mask" "B.Paste")
			(roundrect_rratio 0.25)
			(net 364 "/X710-AT2 Misc/NCSI.ARB_OUT")
			(pintype "passive")
		)
		(pad "2" smd roundrect
			(at 0.48 0 180)
			(size 0.59 0.64)
			(layers "B.Cu" "B.Mask" "B.Paste")
			(roundrect_rratio 0.25)
			(net 159 "Net-(U9D-NCSI_ARB_OUT)")
			(pintype "passive")
		)
	)
	(footprint "antmicro-footprints:R_0402_1005Metric"
		(layer "B.Cu")
		(at 110.49 88.86 90)
		(descr "Resistor SMD 0402")
		(tags "resistor SMD 0402")
		(property "Reference" "R133"
			(at -3.58 -0.38 90)
			(layer "B.SilkS")
			(effects
				(font
					(size 0.7 0.7)
					(thickness 0.15)
				)
				(justify right top mirror)
			)
		)
		(property "Value" "R_10k_0402"
			(at -1.011843 -1.772046 90)
			(layer "B.Fab")
			(hide yes)
			(effects
				(font
					(size 0.7 0.7)
					(thickness 0.15)
				)
				(justify right top mirror)
			)
		)
		(property "Datasheet" "https://www.bourns.com/docs/product-datasheets/cr.pdf"
			(at 0 0 90)
			(layer "B.Fab")
			(hide yes)
			(effects
				(font
					(size 1.27 1.27)
					(thickness 0.15)
				)
				(justify mirror)
			)
		)
		(property "Description" "SMD Chip Resistor, 10 kohm, ± 1%, 62.5 mW, 0402 [1005 Metric], Thick Film, General Purpose"
			(at 0 0 90)
			(layer "B.Fab")
			(hide yes)
			(effects
				(font
					(size 1.27 1.27)
					(thickness 0.15)
				)
				(justify mirror)
			)
		)
		(property "MPN" "CR0402-FX-1002GLF"
			(at 0 0 90)
			(unlocked yes)
			(layer "B.Fab")
			(hide yes)
			(effects
				(font
					(size 1 1)
					(thickness 0.15)
				)
				(justify mirror)
			)
		)
		(property "Manufacturer" "Bourns"
			(at 0 0 90)
			(unlocked yes)
			(layer "B.Fab")
			(hide yes)
			(effects
				(font
					(size 1 1)
					(thickness 0.15)
				)
				(justify mirror)
			)
		)
		(property "License" "Apache-2.0"
			(at 0 0 90)
			(unlocked yes)
			(layer "B.Fab")
			(hide yes)
			(effects
				(font
					(size 1 1)
					(thickness 0.15)
				)
				(justify mirror)
			)
		)
		(property "Author" "Antmicro"
			(at 0 0 90)
			(unlocked yes)
			(layer "B.Fab")
			(hide yes)
			(effects
				(font
					(size 1 1)
					(thickness 0.15)
				)
				(justify mirror)
			)
		)
		(property "Val" "10k"
			(at 0 0 90)
			(unlocked yes)
			(layer "B.Fab")
			(hide yes)
			(effects
				(font
					(size 1 1)
					(thickness 0.15)
				)
				(justify mirror)
			)
		)
		(property "Tolerance" "1%"
			(at 0 0 90)
			(unlocked yes)
			(layer "B.Fab")
			(hide yes)
			(effects
				(font
					(size 1 1)
					(thickness 0.15)
				)
				(justify mirror)
			)
		)
		(sheetname "/X710-AT2 RSVD/")
		(sheetfile "x710-at2-rsvd.kicad_sch")
		(attr smd)
		(fp_rect
			(start -0.925 0.47)
			(end 0.925 -0.47)
			(stroke
				(width 0.05)
				(type default)
			)
			(fill no)
			(layer "B.CrtYd")
		)
		(fp_rect
			(start -0.5 0.25)
			(end 0.5 -0.25)
			(stroke
				(width 0.15)
				(type solid)
			)
			(fill no)
			(layer "B.Fab")
		)
		(pad "1" smd roundrect
			(at -0.48 0 90)
			(size 0.59 0.64)
			(layers "B.Cu" "B.Mask" "B.Paste")
			(roundrect_rratio 0.25)
			(net 28 "GND")
			(pintype "passive")
		)
		(pad "2" smd roundrect
			(at 0.48 0 90)
			(size 0.59 0.64)
			(layers "B.Cu" "B.Mask" "B.Paste")
			(roundrect_rratio 0.25)
			(net 121 "/X710-AT2 RSVD/DEBUG_Y16")
			(pintype "passive")
		)
	)
	(footprint "antmicro-footprints:TP_SMD_0.75mm"
		(layer "B.Cu")
		(at 87 106.35 90)
		(property "Reference" "TP10"
			(at 1.22 -2.29 180)
			(layer "B.SilkS")
			(effects
				(font
					(size 0.7 0.7)
					(thickness 0.15)
				)
				(justify right top mirror)
			)
		)
		(property "Value" "TP_0.75mm_SMD"
			(at 0 -1.2 90)
			(layer "B.Fab")
			(hide yes)
			(effects
				(font
					(size 0.7 0.7)
					(thickness 0.15)
				)
				(justify right top mirror)
			)
		)
		(property "Description" "SMT test point"
			(at 0 0 90)
			(layer "B.Fab")
			(hide yes)
			(effects
				(font
					(size 1.27 1.27)
					(thickness 0.15)
				)
				(justify mirror)
			)
		)
		(property "MPN" ""
			(at 0 0 90)
			(unlocked yes)
			(layer "B.Fab")
			(hide yes)
			(effects
				(font
					(size 1 1)
					(thickness 0.15)
				)
				(justify mirror)
			)
		)
		(property "Manufacturer" ""
			(at 0 0 90)
			(unlocked yes)
			(layer "B.Fab")
			(hide yes)
			(effects
				(font
					(size 1 1)
					(thickness 0.15)
				)
				(justify mirror)
			)
		)
		(property "Author" "Antmicro"
			(at 0 0 90)
			(unlocked yes)
			(layer "B.Fab")
			(hide yes)
			(effects
				(font
					(size 1 1)
					(thickness 0.15)
				)
				(justify mirror)
			)
		)
		(property "License" "Apache-2.0"
			(at 0 0 90)
			(unlocked yes)
			(layer "B.Fab")
			(hide yes)
			(effects
				(font
					(size 1 1)
					(thickness 0.15)
				)
				(justify mirror)
			)
		)
		(sheetname "/X710-AT2 Misc/")
		(sheetfile "x710-at2-mics.kicad_sch")
		(attr exclude_from_pos_files exclude_from_bom)
		(fp_circle
			(center 0 0)
			(end 0.475 0)
			(stroke
				(width 0.05)
				(type default)
			)
			(fill no)
			(layer "B.CrtYd")
		)
		(pad "1" smd circle
			(at 0 0 90)
			(size 0.75 0.75)
			(layers "B.Cu" "B.Mask")
			(net 134 "/X710-AT2 Misc/PHY_TCK")
			(pinfunction "1")
			(pintype "passive")
		)
	)
	(footprint "antmicro-footprints:TP_SMD_1mm"
		(layer "B.Cu")
		(at 80.24 72.3 -90)
		(property "Reference" "TP28"
			(at -1.84 7.148102 90)
			(layer "B.SilkS")
			(effects
				(font
					(size 0.7 0.7)
					(thickness 0.15)
				)
				(justify left bottom mirror)
			)
		)
		(property "Value" "TP_1mm_SMD"
			(at 0 -1.4 90)
			(layer "B.Fab")
			(hide yes)
			(effects
				(font
					(size 0.7 0.7)
					(thickness 0.15)
				)
				(justify left bottom mirror)
			)
		)
		(property "Description" "Test point 1mm SMD"
			(at 0 0 90)
			(layer "B.Fab")
			(hide yes)
			(effects
				(font
					(size 1.27 1.27)
					(thickness 0.15)
				)
				(justify mirror)
			)
		)
		(property "MPN" ""
			(at 0 0 90)
			(unlocked yes)
			(layer "B.Fab")
			(hide yes)
			(effects
				(font
					(size 1 1)
					(thickness 0.15)
				)
				(justify mirror)
			)
		)
		(property "Manufacturer" ""
			(at 0 0 90)
			(unlocked yes)
			(layer "B.Fab")
			(hide yes)
			(effects
				(font
					(size 1 1)
					(thickness 0.15)
				)
				(justify mirror)
			)
		)
		(property "Author" "Antmicro"
			(at 0 0 90)
			(unlocked yes)
			(layer "B.Fab")
			(hide yes)
			(effects
				(font
					(size 1 1)
					(thickness 0.15)
				)
				(justify mirror)
			)
		)
		(property "License" "Apache-2.0"
			(at 0 0 90)
			(unlocked yes)
			(layer "B.Fab")
			(hide yes)
			(effects
				(font
					(size 1 1)
					(thickness 0.15)
				)
				(justify mirror)
			)
		)
		(sheetname "/Power/")
		(sheetfile "power.kicad_sch")
		(attr exclude_from_pos_files exclude_from_bom)
		(fp_circle
			(center 0 0)
			(end 0.6 0)
			(stroke
				(width 0.05)
				(type default)
			)
			(fill no)
			(layer "B.CrtYd")
		)
		(pad "1" smd circle
			(at 0 0 270)
			(size 1 1)
			(layers "B.Cu" "B.Mask")
			(net 351 "/Power/+5V_USB")
			(pinfunction "1")
			(pintype "passive")
		)
	)
)
